(kicad_pcb
	(version 20260206)
	(generator "pcbnew")
	(generator_version "10.0")
	(general
		(thickness 1.6)
		(legacy_teardrops no)
	)
	(paper "A4")
	(title_block
		(title "03242023_DA0F0TMBIJ0_F0T_Motherboard_J_brd_V01_OCP.brd")
		(comment 1 "Grand Teton / footprints 5700-5705 of 6105")
	)
	(layers
		(0 "F.Cu" signal "TOP")
		(4 "In1.Cu" signal "GND")
		(6 "In2.Cu" signal "IN1")
		(8 "In3.Cu" signal "GND1")
		(10 "In4.Cu" signal "IN2")
		(12 "In5.Cu" signal "GND2")
		(14 "In6.Cu" signal "IN3")
		(16 "In7.Cu" signal "GND3")
		(18 "In8.Cu" signal "VCC")
		(20 "In9.Cu" signal "VCC1")
		(22 "In10.Cu" signal "GND4")
		(24 "In11.Cu" signal "IN4")
		(26 "In12.Cu" signal "GND5")
		(28 "In13.Cu" signal "IN5")
		(30 "In14.Cu" signal "GND6")
		(32 "In15.Cu" signal "IN6")
		(34 "In16.Cu" signal "GND7")
		(2 "B.Cu" signal "BOTTOM")
		(9 "F.Adhes" user "F.Adhesive")
		(11 "B.Adhes" user "B.Adhesive")
		(13 "F.Paste" user "Package Geometry/Pastemask Top")
		(15 "B.Paste" user "Package Geometry/Pastemask Bottom")
		(5 "F.SilkS" user "Ref Des/Silkscreen Top")
		(7 "B.SilkS" user "Ref Des/Silkscreen Bottom")
		(1 "F.Mask" user "Board Geometry/Soldermask Top")
		(3 "B.Mask" user "Board Geometry/Soldermask Bottom")
		(17 "Dwgs.User" user "User.Drawings")
		(19 "Cmts.User" user "User.Comments")
		(21 "Eco1.User" user "User.Eco1")
		(23 "Eco2.User" user "User.Eco2")
		(25 "Edge.Cuts" user "Board Geometry/Outline")
		(27 "Margin" user)
		(31 "F.CrtYd" user "Package Geometry/Place Bound Top")
		(29 "B.CrtYd" user "Package Geometry/Place Bound Bottom")
		(35 "F.Fab" user "Ref Des/Assembly Top")
		(33 "B.Fab" user "Ref Des/Assembly Bottom")
	)
	(footprint ""
		(layer "B.Cu")
		(at 30.226 -163.261548)
		(property "Reference" "PR4257"
			(at 0 0 0)
			(layer "B.SilkS")
			(hide yes)
			(effects
				(font
					(size 1.27 1.27)
				)
				(justify mirror)
			)
		)
		(property "Value" ""
			(at 0 0 0)
			(layer "B.Fab")
			(effects
				(font
					(size 1.27 1.27)
				)
				(justify mirror)
			)
		)
		(duplicate_pad_numbers_are_jumpers no)
		(fp_line
			(start -0.7874 -0.4064)
			(end -0.7874 0.4064)
			(stroke
				(width 0.1524)
				(type default)
			)
			(layer "B.SilkS")
		)
		(fp_line
			(start -0.7874 0.4064)
			(end 0.7874 0.4064)
			(stroke
				(width 0.1524)
				(type default)
			)
			(layer "B.SilkS")
		)
		(fp_line
			(start 0.7874 -0.4064)
			(end -0.7874 -0.4064)
			(stroke
				(width 0.1524)
				(type default)
			)
			(layer "B.SilkS")
		)
		(fp_line
			(start 0.7874 0.4064)
			(end 0.7874 -0.4064)
			(stroke
				(width 0.1524)
				(type default)
			)
			(layer "B.SilkS")
		)
		(fp_line
			(start -0.67945 -0.3048)
			(end -0.67945 0.3048)
			(stroke
				(width 0.1)
				(type default)
			)
			(layer "B.Fab")
		)
		(fp_line
			(start -0.67945 0.3048)
			(end -0.120396 0.3048)
			(stroke
				(width 0.1)
				(type default)
			)
			(layer "B.Fab")
		)
		(fp_line
			(start -0.12065 -0.3048)
			(end -0.67945 -0.3048)
			(stroke
				(width 0.1)
				(type default)
			)
			(layer "B.Fab")
		)
		(fp_line
			(start -0.12065 -0.2794)
			(end -0.12065 -0.3048)
			(stroke
				(width 0.1)
				(type default)
			)
			(layer "B.Fab")
		)
		(fp_line
			(start -0.120396 0.2794)
			(end 0.12065 0.2794)
			(stroke
				(width 0.1)
				(type default)
			)
			(layer "B.Fab")
		)
		(fp_line
			(start -0.120396 0.3048)
			(end -0.120396 0.2794)
			(stroke
				(width 0.1)
				(type default)
			)
			(layer "B.Fab")
		)
		(fp_line
			(start 0.12065 -0.305054)
			(end 0.12065 -0.2794)
			(stroke
				(width 0.1)
				(type default)
			)
			(layer "B.Fab")
		)
		(fp_line
			(start 0.12065 -0.2794)
			(end -0.12065 -0.2794)
			(stroke
				(width 0.1)
				(type default)
			)
			(layer "B.Fab")
		)
		(fp_line
			(start 0.12065 0.2794)
			(end 0.12065 0.3048)
			(stroke
				(width 0.1)
				(type default)
			)
			(layer "B.Fab")
		)
		(fp_line
			(start 0.12065 0.3048)
			(end 0.67945 0.3048)
			(stroke
				(width 0.1)
				(type default)
			)
			(layer "B.Fab")
		)
		(fp_line
			(start 0.67945 -0.305054)
			(end 0.12065 -0.305054)
			(stroke
				(width 0.1)
				(type default)
			)
			(layer "B.Fab")
		)
		(fp_line
			(start 0.67945 0.3048)
			(end 0.67945 -0.305054)
			(stroke
				(width 0.1)
				(type default)
			)
			(layer "B.Fab")
		)
		(pad "1" smd circle
			(at 0.40005 0 180)
			(size 0 0)
			(layers "B.Cu" "B.Mask" "B.Paste")
			(net "NC_PVCCD_HV_CPU1_ACSP8")
		)
		(pad "2" smd circle
			(at -0.40005 0 180)
			(size 0 0)
			(layers "B.Cu" "B.Mask" "B.Paste")
			(net "GND")
		)
	)
	(footprint ""
		(layer "B.Cu")
		(at 208.56448 -35.804348 90)
		(property "Reference" "C2019"
			(at 0 0 90)
			(layer "B.SilkS")
			(hide yes)
			(effects
				(font
					(size 1.27 1.27)
				)
				(justify mirror)
			)
		)
		(property "Value" ""
			(at 0 0 90)
			(layer "B.Fab")
			(effects
				(font
					(size 1.27 1.27)
				)
				(justify mirror)
			)
		)
		(duplicate_pad_numbers_are_jumpers no)
		(fp_line
			(start 0.7874 -0.4064)
			(end -0.7874 -0.4064)
			(stroke
				(width 0.1524)
				(type default)
			)
			(layer "B.SilkS")
		)
		(fp_line
			(start -0.7874 -0.4064)
			(end -0.7874 0.4064)
			(stroke
				(width 0.1524)
				(type default)
			)
			(layer "B.SilkS")
		)
		(fp_line
			(start 0.7874 0.4064)
			(end 0.7874 -0.4064)
			(stroke
				(width 0.1524)
				(type default)
			)
			(layer "B.SilkS")
		)
		(fp_line
			(start -0.7874 0.4064)
			(end 0.7874 0.4064)
			(stroke
				(width 0.1524)
				(type default)
			)
			(layer "B.SilkS")
		)
		(fp_line
			(start 0.67945 -0.305054)
			(end 0.12065 -0.305054)
			(stroke
				(width 0.1)
				(type default)
			)
			(layer "B.Fab")
		)
		(fp_line
			(start 0.12065 -0.305054)
			(end 0.12065 -0.2794)
			(stroke
				(width 0.1)
				(type default)
			)
			(layer "B.Fab")
		)
		(fp_line
			(start -0.12065 -0.3048)
			(end -0.67945 -0.3048)
			(stroke
				(width 0.1)
				(type default)
			)
			(layer "B.Fab")
		)
		(fp_line
			(start -0.67945 -0.3048)
			(end -0.67945 0.3048)
			(stroke
				(width 0.1)
				(type default)
			)
			(layer "B.Fab")
		)
		(fp_line
			(start 0.12065 -0.2794)
			(end -0.12065 -0.2794)
			(stroke
				(width 0.1)
				(type default)
			)
			(layer "B.Fab")
		)
		(fp_line
			(start -0.12065 -0.2794)
			(end -0.12065 -0.3048)
			(stroke
				(width 0.1)
				(type default)
			)
			(layer "B.Fab")
		)
		(fp_line
			(start 0.12065 0.2794)
			(end 0.12065 0.3048)
			(stroke
				(width 0.1)
				(type default)
			)
			(layer "B.Fab")
		)
		(fp_line
			(start -0.120396 0.2794)
			(end 0.12065 0.2794)
			(stroke
				(width 0.1)
				(type default)
			)
			(layer "B.Fab")
		)
		(fp_line
			(start 0.67945 0.3048)
			(end 0.67945 -0.305054)
			(stroke
				(width 0.1)
				(type default)
			)
			(layer "B.Fab")
		)
		(fp_line
			(start 0.12065 0.3048)
			(end 0.67945 0.3048)
			(stroke
				(width 0.1)
				(type default)
			)
			(layer "B.Fab")
		)
		(fp_line
			(start -0.120396 0.3048)
			(end -0.120396 0.2794)
			(stroke
				(width 0.1)
				(type default)
			)
			(layer "B.Fab")
		)
		(fp_line
			(start -0.67945 0.3048)
			(end -0.120396 0.3048)
			(stroke
				(width 0.1)
				(type default)
			)
			(layer "B.Fab")
		)
		(pad "1" smd circle
			(at 0.40005 0 270)
			(size 0 0)
			(layers "B.Cu" "B.Mask" "B.Paste")
			(net "P12V_SCM_R")
		)
		(pad "2" smd circle
			(at -0.40005 0 270)
			(size 0 0)
			(layers "B.Cu" "B.Mask" "B.Paste")
			(net "GND")
		)
	)
	(footprint ""
		(layer "B.Cu")
		(at 308.085998 -192.60947 90)
		(property "Reference" "R17"
			(at 0 0 90)
			(layer "B.SilkS")
			(hide yes)
			(effects
				(font
					(size 1.27 1.27)
				)
				(justify mirror)
			)
		)
		(property "Value" ""
			(at 0 0 90)
			(layer "B.Fab")
			(effects
				(font
					(size 1.27 1.27)
				)
				(justify mirror)
			)
		)
		(duplicate_pad_numbers_are_jumpers no)
		(fp_line
			(start 0.7874 -0.4064)
			(end -0.7874 -0.4064)
			(stroke
				(width 0.1524)
				(type default)
			)
			(layer "B.SilkS")
		)
		(fp_line
			(start -0.7874 -0.4064)
			(end -0.7874 0.4064)
			(stroke
				(width 0.1524)
				(type default)
			)
			(layer "B.SilkS")
		)
		(fp_line
			(start 0.7874 0.4064)
			(end 0.7874 -0.4064)
			(stroke
				(width 0.1524)
				(type default)
			)
			(layer "B.SilkS")
		)
		(fp_line
			(start -0.7874 0.4064)
			(end 0.7874 0.4064)
			(stroke
				(width 0.1524)
				(type default)
			)
			(layer "B.SilkS")
		)
		(fp_line
			(start 0.67945 -0.305054)
			(end 0.12065 -0.305054)
			(stroke
				(width 0.1)
				(type default)
			)
			(layer "B.Fab")
		)
		(fp_line
			(start 0.12065 -0.305054)
			(end 0.12065 -0.2794)
			(stroke
				(width 0.1)
				(type default)
			)
			(layer "B.Fab")
		)
		(fp_line
			(start -0.12065 -0.3048)
			(end -0.67945 -0.3048)
			(stroke
				(width 0.1)
				(type default)
			)
			(layer "B.Fab")
		)
		(fp_line
			(start -0.67945 -0.3048)
			(end -0.67945 0.3048)
			(stroke
				(width 0.1)
				(type default)
			)
			(layer "B.Fab")
		)
		(fp_line
			(start 0.12065 -0.2794)
			(end -0.12065 -0.2794)
			(stroke
				(width 0.1)
				(type default)
			)
			(layer "B.Fab")
		)
		(fp_line
			(start -0.12065 -0.2794)
			(end -0.12065 -0.3048)
			(stroke
				(width 0.1)
				(type default)
			)
			(layer "B.Fab")
		)
		(fp_line
			(start 0.12065 0.2794)
			(end 0.12065 0.3048)
			(stroke
				(width 0.1)
				(type default)
			)
			(layer "B.Fab")
		)
		(fp_line
			(start -0.120396 0.2794)
			(end 0.12065 0.2794)
			(stroke
				(width 0.1)
				(type default)
			)
			(layer "B.Fab")
		)
		(fp_line
			(start 0.67945 0.3048)
			(end 0.67945 -0.305054)
			(stroke
				(width 0.1)
				(type default)
			)
			(layer "B.Fab")
		)
		(fp_line
			(start 0.12065 0.3048)
			(end 0.67945 0.3048)
			(stroke
				(width 0.1)
				(type default)
			)
			(layer "B.Fab")
		)
		(fp_line
			(start -0.120396 0.3048)
			(end -0.120396 0.2794)
			(stroke
				(width 0.1)
				(type default)
			)
			(layer "B.Fab")
		)
		(fp_line
			(start -0.67945 0.3048)
			(end -0.120396 0.3048)
			(stroke
				(width 0.1)
				(type default)
			)
			(layer "B.Fab")
		)
		(pad "1" smd circle
			(at 0.40005 0 270)
			(size 0 0)
			(layers "B.Cu" "B.Mask" "B.Paste")
			(net "SVID_ALERT1_CPU0_N")
		)
		(pad "2" smd circle
			(at -0.40005 0 270)
			(size 0 0)
			(layers "B.Cu" "B.Mask" "B.Paste")
			(net "SVID_ALERT1_CPU0_R_N")
		)
	)
	(footprint ""
		(layer "B.Cu")
		(at 235.23448 -423.001948 90)
		(property "Reference" "C2295"
			(at 0 0 90)
			(layer "B.SilkS")
			(hide yes)
			(effects
				(font
					(size 1.27 1.27)
				)
				(justify mirror)
			)
		)
		(property "Value" ""
			(at 0 0 90)
			(layer "B.Fab")
			(effects
				(font
					(size 1.27 1.27)
				)
				(justify mirror)
			)
		)
		(duplicate_pad_numbers_are_jumpers no)
		(fp_line
			(start 0.7874 -0.4064)
			(end -0.7874 -0.4064)
			(stroke
				(width 0.1524)
				(type default)
			)
			(layer "B.SilkS")
		)
		(fp_line
			(start -0.7874 -0.4064)
			(end -0.7874 0.4064)
			(stroke
				(width 0.1524)
				(type default)
			)
			(layer "B.SilkS")
		)
		(fp_line
			(start 0.7874 0.4064)
			(end 0.7874 -0.4064)
			(stroke
				(width 0.1524)
				(type default)
			)
			(layer "B.SilkS")
		)
		(fp_line
			(start -0.7874 0.4064)
			(end 0.7874 0.4064)
			(stroke
				(width 0.1524)
				(type default)
			)
			(layer "B.SilkS")
		)
		(fp_line
			(start 0.67945 -0.305054)
			(end 0.12065 -0.305054)
			(stroke
				(width 0.1)
				(type default)
			)
			(layer "B.Fab")
		)
		(fp_line
			(start 0.12065 -0.305054)
			(end 0.12065 -0.2794)
			(stroke
				(width 0.1)
				(type default)
			)
			(layer "B.Fab")
		)
		(fp_line
			(start -0.12065 -0.3048)
			(end -0.67945 -0.3048)
			(stroke
				(width 0.1)
				(type default)
			)
			(layer "B.Fab")
		)
		(fp_line
			(start -0.67945 -0.3048)
			(end -0.67945 0.3048)
			(stroke
				(width 0.1)
				(type default)
			)
			(layer "B.Fab")
		)
		(fp_line
			(start 0.12065 -0.2794)
			(end -0.12065 -0.2794)
			(stroke
				(width 0.1)
				(type default)
			)
			(layer "B.Fab")
		)
		(fp_line
			(start -0.12065 -0.2794)
			(end -0.12065 -0.3048)
			(stroke
				(width 0.1)
				(type default)
			)
			(layer "B.Fab")
		)
		(fp_line
			(start 0.12065 0.2794)
			(end 0.12065 0.3048)
			(stroke
				(width 0.1)
				(type default)
			)
			(layer "B.Fab")
		)
		(fp_line
			(start -0.120396 0.2794)
			(end 0.12065 0.2794)
			(stroke
				(width 0.1)
				(type default)
			)
			(layer "B.Fab")
		)
		(fp_line
			(start 0.67945 0.3048)
			(end 0.67945 -0.305054)
			(stroke
				(width 0.1)
				(type default)
			)
			(layer "B.Fab")
		)
		(fp_line
			(start 0.12065 0.3048)
			(end 0.67945 0.3048)
			(stroke
				(width 0.1)
				(type default)
			)
			(layer "B.Fab")
		)
		(fp_line
			(start -0.120396 0.3048)
			(end -0.120396 0.2794)
			(stroke
				(width 0.1)
				(type default)
			)
			(layer "B.Fab")
		)
		(fp_line
			(start -0.67945 0.3048)
			(end -0.120396 0.3048)
			(stroke
				(width 0.1)
				(type default)
			)
			(layer "B.Fab")
		)
		(pad "1" smd circle
			(at 0.40005 0 270)
			(size 0 0)
			(layers "B.Cu" "B.Mask" "B.Paste")
			(net "HPDB_HSC_PWRGD_R")
		)
		(pad "2" smd circle
			(at -0.40005 0 270)
			(size 0 0)
			(layers "B.Cu" "B.Mask" "B.Paste")
			(net "GND")
		)
	)
	(footprint ""
		(layer "B.Cu")
		(at 163.66109 -318.717422 90)
		(property "Reference" "R902"
			(at 0 0 90)
			(layer "B.SilkS")
			(hide yes)
			(effects
				(font
					(size 1.27 1.27)
				)
				(justify mirror)
			)
		)
		(property "Value" ""
			(at 0 0 90)
			(layer "B.Fab")
			(effects
				(font
					(size 1.27 1.27)
				)
				(justify mirror)
			)
		)
		(duplicate_pad_numbers_are_jumpers no)
		(fp_line
			(start 0.7874 -0.4064)
			(end -0.7874 -0.4064)
			(stroke
				(width 0.1524)
				(type default)
			)
			(layer "B.SilkS")
		)
		(fp_line
			(start -0.7874 -0.4064)
			(end -0.7874 0.4064)
			(stroke
				(width 0.1524)
				(type default)
			)
			(layer "B.SilkS")
		)
		(fp_line
			(start 0.7874 0.4064)
			(end 0.7874 -0.4064)
			(stroke
				(width 0.1524)
				(type default)
			)
			(layer "B.SilkS")
		)
		(fp_line
			(start -0.7874 0.4064)
			(end 0.7874 0.4064)
			(stroke
				(width 0.1524)
				(type default)
			)
			(layer "B.SilkS")
		)
		(fp_line
			(start 0.67945 -0.305054)
			(end 0.12065 -0.305054)
			(stroke
				(width 0.1)
				(type default)
			)
			(layer "B.Fab")
		)
		(fp_line
			(start 0.12065 -0.305054)
			(end 0.12065 -0.2794)
			(stroke
				(width 0.1)
				(type default)
			)
			(layer "B.Fab")
		)
		(fp_line
			(start -0.12065 -0.3048)
			(end -0.67945 -0.3048)
			(stroke
				(width 0.1)
				(type default)
			)
			(layer "B.Fab")
		)
		(fp_line
			(start -0.67945 -0.3048)
			(end -0.67945 0.3048)
			(stroke
				(width 0.1)
				(type default)
			)
			(layer "B.Fab")
		)
		(fp_line
			(start 0.12065 -0.2794)
			(end -0.12065 -0.2794)
			(stroke
				(width 0.1)
				(type default)
			)
			(layer "B.Fab")
		)
		(fp_line
			(start -0.12065 -0.2794)
			(end -0.12065 -0.3048)
			(stroke
				(width 0.1)
				(type default)
			)
			(layer "B.Fab")
		)
		(fp_line
			(start 0.12065 0.2794)
			(end 0.12065 0.3048)
			(stroke
				(width 0.1)
				(type default)
			)
			(layer "B.Fab")
		)
		(fp_line
			(start -0.120396 0.2794)
			(end 0.12065 0.2794)
			(stroke
				(width 0.1)
				(type default)
			)
			(layer "B.Fab")
		)
		(fp_line
			(start 0.67945 0.3048)
			(end 0.67945 -0.305054)
			(stroke
				(width 0.1)
				(type default)
			)
			(layer "B.Fab")
		)
		(fp_line
			(start 0.12065 0.3048)
			(end 0.67945 0.3048)
			(stroke
				(width 0.1)
				(type default)
			)
			(layer "B.Fab")
		)
		(fp_line
			(start -0.120396 0.3048)
			(end -0.120396 0.2794)
			(stroke
				(width 0.1)
				(type default)
			)
			(layer "B.Fab")
		)
		(fp_line
			(start -0.67945 0.3048)
			(end -0.120396 0.3048)
			(stroke
				(width 0.1)
				(type default)
			)
			(layer "B.Fab")
		)
		(pad "1" smd circle
			(at 0.40005 0 270)
			(size 0 0)
			(layers "B.Cu" "B.Mask" "B.Paste")
			(net "PWRGD_CHE_CPU1_DIMM2")
		)
		(pad "2" smd circle
			(at -0.40005 0 270)
			(size 0 0)
			(layers "B.Cu" "B.Mask" "B.Paste")
			(net "PWRGD_FAIL_CPU1_EF")
		)
	)
	(footprint ""
		(layer "B.Cu")
		(at 429.14951 -353.05111 -90)
		(property "Reference" "PC1183_P0_3"
			(at 0 0 90)
			(layer "B.SilkS")
			(hide yes)
			(effects
				(font
					(size 1.27 1.27)
				)
				(justify mirror)
			)
		)
		(property "Value" ""
			(at 0 0 90)
			(layer "B.Fab")
			(effects
				(font
					(size 1.27 1.27)
				)
				(justify mirror)
			)
		)
		(duplicate_pad_numbers_are_jumpers no)
		(fp_line
			(start -0.7874 0.4064)
			(end 0.7874 0.4064)
			(stroke
				(width 0.1524)
				(type default)
			)
			(layer "B.SilkS")
		)
		(fp_line
			(start 0.7874 0.4064)
			(end 0.7874 -0.4064)
			(stroke
				(width 0.1524)
				(type default)
			)
			(layer "B.SilkS")
		)
		(fp_line
			(start -0.7874 -0.4064)
			(end -0.7874 0.4064)
			(stroke
				(width 0.1524)
				(type default)
			)
			(layer "B.SilkS")
		)
		(fp_line
			(start 0.7874 -0.4064)
			(end -0.7874 -0.4064)
			(stroke
				(width 0.1524)
				(type default)
			)
			(layer "B.SilkS")
		)
		(fp_line
			(start -0.67945 0.3048)
			(end -0.120396 0.3048)
			(stroke
				(width 0.1)
				(type default)
			)
			(layer "B.Fab")
		)
		(fp_line
			(start -0.120396 0.3048)
			(end -0.120396 0.2794)
			(stroke
				(width 0.1)
				(type default)
			)
			(layer "B.Fab")
		)
		(fp_line
			(start 0.12065 0.3048)
			(end 0.67945 0.3048)
			(stroke
				(width 0.1)
				(type default)
			)
			(layer "B.Fab")
		)
		(fp_line
			(start 0.67945 0.3048)
			(end 0.67945 -0.305054)
			(stroke
				(width 0.1)
				(type default)
			)
			(layer "B.Fab")
		)
		(fp_line
			(start -0.120396 0.2794)
			(end 0.12065 0.2794)
			(stroke
				(width 0.1)
				(type default)
			)
			(layer "B.Fab")
		)
		(fp_line
			(start 0.12065 0.2794)
			(end 0.12065 0.3048)
			(stroke
				(width 0.1)
				(type default)
			)
			(layer "B.Fab")
		)
		(fp_line
			(start -0.12065 -0.2794)
			(end -0.12065 -0.3048)
			(stroke
				(width 0.1)
				(type default)
			)
			(layer "B.Fab")
		)
		(fp_line
			(start 0.12065 -0.2794)
			(end -0.12065 -0.2794)
			(stroke
				(width 0.1)
				(type default)
			)
			(layer "B.Fab")
		)
		(fp_line
			(start -0.67945 -0.3048)
			(end -0.67945 0.3048)
			(stroke
				(width 0.1)
				(type default)
			)
			(layer "B.Fab")
		)
		(fp_line
			(start -0.12065 -0.3048)
			(end -0.67945 -0.3048)
			(stroke
				(width 0.1)
				(type default)
			)
			(layer "B.Fab")
		)
		(fp_line
			(start 0.12065 -0.305054)
			(end 0.12065 -0.2794)
			(stroke
				(width 0.1)
				(type default)
			)
			(layer "B.Fab")
		)
		(fp_line
			(start 0.67945 -0.305054)
			(end 0.12065 -0.305054)
			(stroke
				(width 0.1)
				(type default)
			)
			(layer "B.Fab")
		)
		(pad "1" smd circle
			(at 0.40005 0 90)
			(size 0 0)
			(layers "B.Cu" "B.Mask" "B.Paste")
			(net "PVCCFA_EHV_FIVRA_CPU0")
		)
		(pad "2" smd circle
			(at -0.40005 0 90)
			(size 0 0)
			(layers "B.Cu" "B.Mask" "B.Paste")
			(net "GND")
		)
	)
)
